FILE_TYPE = MACRO_DRAWING;
SET COLOR_WIRE YELLOW;
SET COLOR_PROP MONO;
SET COLOR_DOT WHITE;
SET COLOR_ARC YELLOW;
SET COLOR_BODY GREEN;
SET COLOR_NOTE MONO;
SET PROP_DISPLAY VALUE;
SET PAGE_NUMBER P177;
FORCEADD OFFPAGE..1
(-9000 6225);
FORCEPROP 2 LAST $XR0 120 
J 0
(-9252 6225);
DISPLAY 0.638298 (-9252 6225);
PAINT MONO (-9252 6225);
FORCEPROP 2 LAST CDS_LIB mstr_standard
J 0
(-9000 6225);
DISPLAY 1.361702 (-9000 6225);
PAINT ORANGE (-9000 6225);
DISPLAY INVISIBLE (-9000 6225);
FORCEPROP 2 LAST ROOM MIO_CHASSIS
J 0
(-9200 6275);
DISPLAY 1.404255 (-9200 6275);
PAINT ORANGE (-9200 6275);
DISPLAY INVISIBLE (-9200 6275);
FORCEPROP 2 LAST PATH I1
J 0
(-9250 6275);
DISPLAY 1.021277 (-9250 6275);
PAINT ORANGE (-9250 6275);
DISPLAY INVISIBLE (-9250 6275);
FORCEPROP 1 LAST OFFPAGE TRUE
J 0
(-8675 6100);
PAINT GREEN (-8675 6100);
DISPLAY INVISIBLE (-8675 6100);
FORCEPROP 1 LAST COMMENT_BODY TRUE
J 0
(-8875 6125);
DISPLAY 1.170213 (-8875 6125);
PAINT GREEN (-8875 6125);
DISPLAY INVISIBLE (-8875 6125);
FORCEADD P3V3..1
(-6975 6775);
FORCEPROP 3 LASTPIN (-6975 6725) SIG_NAME P3V3\g
J 0
(-6965 6735);
DISPLAY 0.659574 (-6965 6735);
PAINT MONO (-6965 6735);
DISPLAY INVISIBLE (-6965 6735);
FORCEPROP 1 LAST VOLTAGE +3.3
J 0
(-6975 6775);
PAINT SKYBLUE (-6975 6775);
DISPLAY INVISIBLE (-6975 6775);
FORCEPROP 1 LAST SIZE 1B
J 0
(-6930 6797);
DISPLAY 0.553191 (-6930 6797);
PAINT GREEN (-6930 6797);
DISPLAY INVISIBLE (-6930 6797);
FORCEPROP 2 LAST CDS_LIB mstr_symbols
J 0
(-6975 6775);
DISPLAY 1.361702 (-6975 6775);
PAINT ORANGE (-6975 6775);
DISPLAY INVISIBLE (-6975 6775);
FORCEPROP 1 LAST PATH I10
J 0
(-6930 6777);
DISPLAY 0.340426 (-6930 6777);
PAINT GREEN (-6930 6777);
DISPLAY INVISIBLE (-6930 6777);
FORCEPROP 2 LAST ROOM SB
J 0
(-7425 6875);
DISPLAY 1.404255 (-7425 6875);
PAINT ORANGE (-7425 6875);
DISPLAY INVISIBLE (-7425 6875);
FORCEPROP 1 LAST BODY_TYPE PLUMBING
J 0
(-7020 6732);
DISPLAY 0.468085 (-7020 6732);
PAINT GREEN (-7020 6732);
DISPLAY INVISIBLE (-7020 6732);
FORCEPROP 1 LAST HDL_POWER P3V3
J 0
(-7300 6650);
DISPLAY 1.170213 (-7300 6650);
PAINT GREEN (-7300 6650);
DISPLAY INVISIBLE (-7300 6650);
FORCEADD CAP_A..1
(-5625 5425);
FORCEPROP 1 LAST LOCATION C1M3
J 0
(-5575 5525);
DISPLAY 0.617021 (-5575 5525);
PAINT AQUA (-5575 5525);
FORCEPROP 1 LAST PART_NUMBER D97712-004
J 0
(-5575 5275);
DISPLAY 0.617021 (-5575 5275);
PAINT BLUE (-5575 5275);
FORCEPROP 1 LAST VALUE 1.0UF
J 0
(-5575 5475);
DISPLAY 0.617021 (-5575 5475);
PAINT SKYBLUE (-5575 5475);
FORCEPROP 1 LAST TOLERANCE 10%
J 0
(-5575 5375);
DISPLAY 0.617021 (-5575 5375);
PAINT SKYBLUE (-5575 5375);
FORCEPROP 1 LAST PACK_TYPE 0402V
J 0
(-5575 5225);
DISPLAY 0.617021 (-5575 5225);
PAINT SKYBLUE (-5575 5225);
FORCEPROP 1 LAST VOLTAGE 6.3V
J 0
(-5575 5425);
DISPLAY 0.617021 (-5575 5425);
PAINT SKYBLUE (-5575 5425);
FORCEPROP 1 LAST MATERIAL X6S
J 0
(-5575 5325);
DISPLAY 0.617021 (-5575 5325);
PAINT SKYBLUE (-5575 5325);
FORCEPROP 1 LASTPIN (-5625 5525) $PN 1
J 0
(-5615 5505);
DISPLAY 0.617021 (-5615 5505);
PAINT MONO (-5615 5505);
FORCEPROP 1 LASTPIN (-5625 5325) $PN 2
J 0
(-5615 5305);
DISPLAY 0.617021 (-5615 5305);
PAINT MONO (-5615 5305);
FORCEPROP 2 LAST CDS_LOCATION C1M3
J 0
(-5575 5525);
DISPLAY 0.617021 (-5575 5525);
PAINT AQUA (-5575 5525);
DISPLAY INVISIBLE (-5575 5525);
FORCEPROP 2 LAST CDS_LIB dev_discrete
J 0
(-5625 5425);
PAINT ORANGE (-5625 5425);
DISPLAY INVISIBLE (-5625 5425);
FORCEPROP 2 LAST CDS_SEC 1
J 0
(-5575 5625);
DISPLAY 1.404255 (-5575 5625);
PAINT ORANGE (-5575 5625);
DISPLAY INVISIBLE (-5575 5625);
FORCEPROP 2 LAST $SEC 1
J 0
(-5575 5625);
DISPLAY 0.936170 (-5575 5625);
PAINT MONO (-5575 5625);
DISPLAY INVISIBLE (-5575 5625);
FORCEPROP 1 LAST PATH I20
J 0
(-5575 5575);
DISPLAY 0.978723 (-5575 5575);
PAINT WHITE (-5575 5575);
DISPLAY INVISIBLE (-5575 5575);
FORCEPROP 2 LAST ROOM MIO_CHASSIS
J 0
(-5575 5575);
DISPLAY 1.404255 (-5575 5575);
PAINT ORANGE (-5575 5575);
DISPLAY INVISIBLE (-5575 5575);
FORCEADD RES..1
(-7900 6225);
FORCEPROP 1 LASTPIN (-8000 6225) $PN 1
J 0
(-7988 6237);
DISPLAY 0.617021 (-7988 6237);
PAINT MONO (-7988 6237);
FORCEPROP 1 LAST MATERIAL CHIP
J 0
(-7850 6075);
DISPLAY 0.617021 (-7850 6075);
PAINT SKYBLUE (-7850 6075);
FORCEPROP 1 LASTPIN (-7800 6225) $PN 2
J 0
(-7838 6237);
DISPLAY 0.617021 (-7838 6237);
PAINT MONO (-7838 6237);
FORCEPROP 1 LAST LOCATION R1M13
J 0
(-8025 6275);
DISPLAY 0.617021 (-8025 6275);
PAINT AQUA (-8025 6275);
FORCEPROP 1 LAST PART_NUMBER G21497-005
J 0
(-8525 6150);
DISPLAY 0.617021 (-8525 6150);
PAINT BLUE (-8525 6150);
FORCEPROP 1 LAST PACK_TYPE 0402
J 0
(-8050 6075);
DISPLAY 0.617021 (-8050 6075);
PAINT SKYBLUE (-8050 6075);
FORCEPROP 1 LAST WATTAGE 1/16W
J 2
(-7925 6175);
DISPLAY 0.617021 (-7925 6175);
PAINT SKYBLUE (-7925 6175);
FORCEPROP 1 LAST TOLERANCE 5%
J 0
(-7850 6175);
DISPLAY 0.617021 (-7850 6175);
PAINT SKYBLUE (-7850 6175);
FORCEPROP 1 LAST VALUE 0.0
J 2
(-7800 6275);
DISPLAY 0.617021 (-7800 6275);
PAINT SKYBLUE (-7800 6275);
FORCEPROP 2 LAST CDS_LIB mstr_discrete
J 0
(-7900 6225);
DISPLAY 1.361702 (-7900 6225);
PAINT ORANGE (-7900 6225);
DISPLAY INVISIBLE (-7900 6225);
FORCEPROP 2 LAST CDS_SEC 1
J 0
(-7950 6425);
DISPLAY 1.404255 (-7950 6425);
PAINT ORANGE (-7950 6425);
DISPLAY INVISIBLE (-7950 6425);
FORCEPROP 2 LAST $SEC 1
J 0
(-7950 6425);
DISPLAY 0.936170 (-7950 6425);
PAINT MONO (-7950 6425);
DISPLAY INVISIBLE (-7950 6425);
FORCEPROP 2 LAST CDS_LOCATION R1M13
J 0
(-8025 6275);
DISPLAY 0.617021 (-8025 6275);
PAINT AQUA (-8025 6275);
DISPLAY INVISIBLE (-8025 6275);
FORCEPROP 1 LAST PATH I3
J 0
(-7950 6375);
DISPLAY 0.978723 (-7950 6375);
PAINT WHITE (-7950 6375);
DISPLAY INVISIBLE (-7950 6375);
FORCEPROP 2 LAST ROOM MIO_CHASSIS
J 0
(-7725 6325);
PAINT PEACH (-7725 6325);
DISPLAY INVISIBLE (-7725 6325);
FORCEADD GND..1
(-3825 8250);
FORCEPROP 3 LASTPIN (-3825 8300) SIG_NAME GND\g
J 0
(-3815 8310);
DISPLAY 0.659574 (-3815 8310);
PAINT MONO (-3815 8310);
DISPLAY INVISIBLE (-3815 8310);
FORCEPROP 1 LAST VOLTAGE 0
J 0
(-3825 8250);
PAINT SKYBLUE (-3825 8250);
DISPLAY INVISIBLE (-3825 8250);
FORCEPROP 2 LAST CDS_LIB mstr_symbols
J 0
(-3825 8250);
DISPLAY 1.765957 (-3825 8250);
PAINT ORANGE (-3825 8250);
DISPLAY INVISIBLE (-3825 8250);
FORCEPROP 1 LAST SIZE 1B
J 0
(-3750 8200);
DISPLAY 0.978723 (-3750 8200);
PAINT ORANGE (-3750 8200);
DISPLAY INVISIBLE (-3750 8200);
FORCEPROP 1 LAST PATH I30
J 0
(-3750 8250);
DISPLAY 0.872340 (-3750 8250);
PAINT AQUA (-3750 8250);
DISPLAY INVISIBLE (-3750 8250);
FORCEPROP 2 LAST ROOM DEBUG
J 0
(-4025 8325);
DISPLAY 0.978723 (-4025 8325);
PAINT ORANGE (-4025 8325);
DISPLAY INVISIBLE (-4025 8325);
FORCEPROP 1 LAST BODY_TYPE PLUMBING
J 0
(-3870 8207);
DISPLAY 0.340426 (-3870 8207);
PAINT GREEN (-3870 8207);
DISPLAY INVISIBLE (-3870 8207);
FORCEPROP 1 LAST HDL_POWER GND
J 0
(-3825 8400);
DISPLAY 0.978723 (-3825 8400);
PAINT GREEN (-3825 8400);
DISPLAY INVISIBLE (-3825 8400);
FORCEADD LED..2
(-3825 8475);
FORCEPROP 1 LAST LOCATION DS9A6
J 0
(-3725 8525);
DISPLAY 0.617021 (-3725 8525);
PAINT AQUA (-3725 8525);
FORCEPROP 1 LAST PART_NUMBER C97278-010
J 0
(-3725 8375);
DISPLAY 0.617021 (-3725 8375);
PAINT BLUE (-3725 8375);
FORCEPROP 1 LAST MATERIAL IC
J 0
(-3725 8425);
DISPLAY 0.617021 (-3725 8425);
PAINT SKYBLUE (-3725 8425);
FORCEPROP 1 LASTPIN (-3825 8375) $PN 2
J 0
(-3800 8350);
DISPLAY 0.617021 (-3800 8350);
PAINT MONO (-3800 8350);
FORCEPROP 1 LASTPIN (-3825 8575) $PN 1
J 0
(-3800 8550);
DISPLAY 0.617021 (-3800 8550);
PAINT MONO (-3800 8550);
FORCEPROP 1 LAST COLOR GREEN
J 0
(-3725 8475);
DISPLAY 0.617021 (-3725 8475);
PAINT BLUE (-3725 8475);
FORCEPROP 1 LAST PACK_TYPE A1LF
J 0
(-3725 8325);
PAINT SKYBLUE (-3725 8325);
DISPLAY INVISIBLE (-3725 8325);
FORCEPROP 2 LAST SEC_TYPE A1LF
J 0
(-3725 8625);
DISPLAY 1.404255 (-3725 8625);
PAINT ORANGE (-3725 8625);
DISPLAY INVISIBLE (-3725 8625);
FORCEPROP 2 LAST CDS_LIB mstr_discrete
J 0
(-3825 8475);
PAINT ORANGE (-3825 8475);
DISPLAY INVISIBLE (-3825 8475);
FORCEPROP 2 LAST SEC 1
J 0
(-3725 8625);
DISPLAY 0.936170 (-3725 8625);
PAINT MONO (-3725 8625);
DISPLAY INVISIBLE (-3725 8625);
FORCEPROP 2 LAST CDS_LOCATION DS9A6
J 0
(-3725 8525);
DISPLAY 0.617021 (-3725 8525);
PAINT AQUA (-3725 8525);
DISPLAY INVISIBLE (-3725 8525);
FORCEPROP 1 LAST PATH I31
J 0
(-3725 8575);
DISPLAY 0.978723 (-3725 8575);
PAINT BLUE (-3725 8575);
DISPLAY INVISIBLE (-3725 8575);
FORCEPROP 2 LAST ROOM MIO_CHASSIS
J 0
(-3725 8565);
DISPLAY 0.787234 (-3725 8565);
PAINT SKYBLUE (-3725 8565);
DISPLAY INVISIBLE (-3725 8565);
FORCEADD RES..2
(-3825 8850);
FORCEPROP 1 LAST LOCATION R1L37
J 0
(-3780 8975);
DISPLAY 0.617021 (-3780 8975);
PAINT AQUA (-3780 8975);
FORCEPROP 1 LAST VALUE 301.0
J 0
(-3780 8925);
DISPLAY 0.617021 (-3780 8925);
PAINT SKYBLUE (-3780 8925);
FORCEPROP 1 LAST TOLERANCE 1%
J 0
(-3780 8875);
DISPLAY 0.617021 (-3780 8875);
PAINT SKYBLUE (-3780 8875);
FORCEPROP 1 LAST PACK_TYPE 0402
J 0
(-3785 8675);
DISPLAY 0.617021 (-3785 8675);
PAINT SKYBLUE (-3785 8675);
FORCEPROP 1 LAST MATERIAL CHIP
J 0
(-3785 8775);
DISPLAY 0.617021 (-3785 8775);
PAINT SKYBLUE (-3785 8775);
FORCEPROP 1 LAST WATTAGE 1/16W
J 0
(-3785 8825);
DISPLAY 0.617021 (-3785 8825);
PAINT SKYBLUE (-3785 8825);
FORCEPROP 1 LAST PART_NUMBER G21796-076
J 0
(-3785 8725);
DISPLAY 0.617021 (-3785 8725);
PAINT BLUE (-3785 8725);
FORCEPROP 2 LAST CDS_LIB mstr_discrete
J 0
(-3825 8850);
PAINT RED (-3825 8850);
DISPLAY INVISIBLE (-3825 8850);
FORCEPROP 0 LAST SIGNAL_MODEL DEFAULT_RESISTOR_332OHM_2_1
J 0
(-3775 9075);
PAINT MONO (-3775 9075);
DISPLAY INVISIBLE (-3775 9075);
FORCEPROP 2 LAST CDS_SEC 1
J 0
(-3775 9075);
DISPLAY 1.404255 (-3775 9075);
PAINT ORANGE (-3775 9075);
DISPLAY INVISIBLE (-3775 9075);
FORCEPROP 2 LAST $SEC 1
J 0
(-3775 9075);
DISPLAY 0.936170 (-3775 9075);
PAINT MONO (-3775 9075);
DISPLAY INVISIBLE (-3775 9075);
FORCEPROP 2 LAST CDS_LOCATION R1L37
J 0
(-3780 8975);
DISPLAY 0.617021 (-3780 8975);
PAINT AQUA (-3780 8975);
DISPLAY INVISIBLE (-3780 8975);
FORCEPROP 1 LAST PATH I33
J 0
(-3775 9025);
DISPLAY 0.978723 (-3775 9025);
PAINT WHITE (-3775 9025);
DISPLAY INVISIBLE (-3775 9025);
FORCEPROP 0 LAST ROOM MIO_CHASSIS
J 0
(-3750 9025);
DISPLAY 0.978723 (-3750 9025);
PAINT ORANGE (-3750 9025);
DISPLAY INVISIBLE (-3750 9025);
FORCEPROP 1 LASTPIN (-3825 8750) $PN 2
J 0
(-3820 8760);
DISPLAY 0.936170 (-3820 8760);
PAINT MONO (-3820 8760);
DISPLAY INVISIBLE (-3820 8760);
FORCEPROP 1 LASTPIN (-3825 8950) $PN 1
J 0
(-3820 8912);
DISPLAY 0.936170 (-3820 8912);
PAINT MONO (-3820 8912);
DISPLAY INVISIBLE (-3820 8912);
FORCEADD P5V_STBY..1
(-3825 9050);
FORCEPROP 3 LASTPIN (-3825 9000) SIG_NAME P5V_STBY\g
J 0
(-3815 9010);
DISPLAY 0.659574 (-3815 9010);
PAINT MONO (-3815 9010);
DISPLAY INVISIBLE (-3815 9010);
FORCEPROP 1 LAST VOLTAGE 5.0V
J 0
(-3870 9007);
DISPLAY 0.340426 (-3870 9007);
PAINT SKYBLUE (-3870 9007);
DISPLAY INVISIBLE (-3870 9007);
FORCEPROP 2 LAST CDS_LIB mstr_symbols
J 0
(-3825 9050);
PAINT ORANGE (-3825 9050);
DISPLAY INVISIBLE (-3825 9050);
FORCEPROP 1 LAST SIZE 1B
J 0
(-3780 9072);
DISPLAY 0.340426 (-3780 9072);
PAINT GREEN (-3780 9072);
DISPLAY INVISIBLE (-3780 9072);
FORCEPROP 1 LAST PATH I36
J 0
(-3780 9052);
DISPLAY 0.340426 (-3780 9052);
PAINT GREEN (-3780 9052);
DISPLAY INVISIBLE (-3780 9052);
FORCEPROP 1 LAST BODY_TYPE PLUMBING
J 0
(-3870 9007);
DISPLAY 0.340426 (-3870 9007);
PAINT GREEN (-3870 9007);
DISPLAY INVISIBLE (-3870 9007);
FORCEPROP 1 LAST HDL_POWER P5V_STBY
J 0
(-4125 8925);
DISPLAY 0.872340 (-4125 8925);
PAINT ORANGE (-4125 8925);
DISPLAY INVISIBLE (-4125 8925);
FORCEADD OFFPAGE..1
(-9000 6325);
FORCEPROP 2 LAST $XR0 120 
J 0
(-9252 6325);
DISPLAY 0.638298 (-9252 6325);
PAINT MONO (-9252 6325);
FORCEPROP 2 LAST CDS_LIB mstr_standard
J 0
(-9000 6325);
DISPLAY 1.361702 (-9000 6325);
PAINT ORANGE (-9000 6325);
DISPLAY INVISIBLE (-9000 6325);
FORCEPROP 2 LAST ROOM MIO_CHASSIS
J 0
(-9200 6375);
DISPLAY 1.404255 (-9200 6375);
PAINT ORANGE (-9200 6375);
DISPLAY INVISIBLE (-9200 6375);
FORCEPROP 2 LAST PATH I4
J 0
(-9250 6375);
DISPLAY 1.021277 (-9250 6375);
PAINT ORANGE (-9250 6375);
DISPLAY INVISIBLE (-9250 6375);
FORCEPROP 1 LAST OFFPAGE TRUE
J 0
(-8675 6200);
PAINT GREEN (-8675 6200);
DISPLAY INVISIBLE (-8675 6200);
FORCEPROP 1 LAST COMMENT_BODY TRUE
J 0
(-8875 6225);
DISPLAY 1.170213 (-8875 6225);
PAINT GREEN (-8875 6225);
DISPLAY INVISIBLE (-8875 6225);
FORCEADD LED..3
(-5550 6275);
FORCEPROP 1 LAST COLOR GREEN
J 0
(-5650 6375);
DISPLAY 0.617021 (-5650 6375);
PAINT BLUE (-5650 6375);
FORCEPROP 1 LAST MATERIAL IC
J 0
(-5650 6425);
DISPLAY 0.617021 (-5650 6425);
PAINT SKYBLUE (-5650 6425);
FORCEPROP 2 LASTPIN (-5450 6275) $PN 2
J 0
(-5440 6285);
DISPLAY 0.617021 (-5440 6285);
PAINT ORANGE (-5440 6285);
FORCEPROP 2 LASTPIN (-5650 6275) $PN 1
J 2
(-5660 6285);
DISPLAY 0.617021 (-5660 6285);
PAINT ORANGE (-5660 6285);
FORCEPROP 1 LAST LOCATION DS9A2
J 0
(-5650 6475);
DISPLAY 0.617021 (-5650 6475);
PAINT AQUA (-5650 6475);
FORCEPROP 1 LAST PART_NUMBER C96565-011
J 0
(-5650 6125);
DISPLAY 0.617021 (-5650 6125);
PAINT BLUE (-5650 6125);
FORCEPROP 0 LAST NEW_PN 83.00320.A70
J 0
(-5650 6575);
DISPLAY 1.021277 (-5650 6575);
PAINT BROWN (-5650 6575);
DISPLAY BOTH (-5650 6575);
FORCEPROP 2 LAST CDS_LOCATION DS9A2
J 0
(-5650 6475);
DISPLAY 0.617021 (-5650 6475);
PAINT AQUA (-5650 6475);
DISPLAY INVISIBLE (-5650 6475);
FORCEPROP 2 LAST CDS_LIB mstr_discrete
J 0
(-5550 6275);
PAINT MONO (-5550 6275);
DISPLAY INVISIBLE (-5550 6275);
FORCEPROP 2 LAST SEC 1
J 0
(-5650 6525);
DISPLAY 0.680851 (-5650 6525);
PAINT MONO (-5650 6525);
DISPLAY INVISIBLE (-5650 6525);
FORCEPROP 2 LAST SEC_TYPE 1NCLF
J 0
(-5650 6525);
DISPLAY 1.021277 (-5650 6525);
PAINT ORANGE (-5650 6525);
DISPLAY INVISIBLE (-5650 6525);
FORCEPROP 1 LAST PATH I42
J 0
(-5200 6425);
DISPLAY 0.978723 (-5200 6425);
PAINT BLUE (-5200 6425);
DISPLAY INVISIBLE (-5200 6425);
FORCEPROP 0 LAST ROOM MIO_CHASSIS
J 0
(-5650 6575);
DISPLAY 1.021277 (-5650 6575);
PAINT ORANGE (-5650 6575);
DISPLAY INVISIBLE (-5650 6575);
FORCEPROP 1 LAST PACK_TYPE 1NCLF
J 0
(-5650 6525);
DISPLAY 0.978723 (-5650 6525);
PAINT SKYBLUE (-5650 6525);
DISPLAY INVISIBLE (-5650 6525);
FORCEADD RES..2
(-4675 6600);
FORCEPROP 1 LAST PART_NUMBER G21796-298
J 0
(-4635 6475);
DISPLAY 0.617021 (-4635 6475);
PAINT BLUE (-4635 6475);
FORCEPROP 1 LASTPIN (-4675 6500) $PN 2
J 0
(-4670 6510);
DISPLAY 0.617021 (-4670 6510);
PAINT ORANGE (-4670 6510);
FORCEPROP 1 LAST PACK_TYPE 0402
J 0
(-4635 6425);
DISPLAY 0.617021 (-4635 6425);
PAINT SKYBLUE (-4635 6425);
FORCEPROP 1 LAST MATERIAL CHIP
J 0
(-4635 6525);
DISPLAY 0.617021 (-4635 6525);
PAINT SKYBLUE (-4635 6525);
FORCEPROP 1 LASTPIN (-4675 6700) $PN 1
J 0
(-4670 6662);
DISPLAY 0.617021 (-4670 6662);
PAINT ORANGE (-4670 6662);
FORCEPROP 1 LAST TOLERANCE 1.0%
J 0
(-4630 6625);
DISPLAY 0.617021 (-4630 6625);
PAINT SKYBLUE (-4630 6625);
FORCEPROP 1 LAST VALUE 64.9
J 0
(-4630 6675);
DISPLAY 0.617021 (-4630 6675);
PAINT SKYBLUE (-4630 6675);
FORCEPROP 1 LAST WATTAGE 1/16W
J 0
(-4635 6575);
DISPLAY 0.617021 (-4635 6575);
PAINT SKYBLUE (-4635 6575);
FORCEPROP 1 LAST LOCATION R1L21
J 0
(-4630 6725);
DISPLAY 0.617021 (-4630 6725);
PAINT AQUA (-4630 6725);
FORCEPROP 0 LAST CONFIG 64.12005.6DL
J 0
(-4650 6350);
DISPLAY 1.021277 (-4650 6350);
PAINT BROWN (-4650 6350);
DISPLAY BOTH (-4650 6350);
FORCEPROP 2 LAST CDS_LIB mstr_discrete
J 0
(-4675 6600);
PAINT MONO (-4675 6600);
DISPLAY INVISIBLE (-4675 6600);
FORCEPROP 2 LAST SEC_TYPE 0402
J 0
(-4625 6825);
DISPLAY 1.021277 (-4625 6825);
PAINT ORANGE (-4625 6825);
DISPLAY INVISIBLE (-4625 6825);
FORCEPROP 2 LAST SEC 1
J 0
(-4625 6825);
DISPLAY 0.680851 (-4625 6825);
PAINT MONO (-4625 6825);
DISPLAY INVISIBLE (-4625 6825);
FORCEPROP 2 LAST CDS_LOCATION R1L21
J 0
(-4630 6725);
DISPLAY 0.617021 (-4630 6725);
PAINT AQUA (-4630 6725);
DISPLAY INVISIBLE (-4630 6725);
FORCEPROP 1 LAST PATH I43
J 0
(-4625 6775);
DISPLAY 0.978723 (-4625 6775);
PAINT WHITE (-4625 6775);
DISPLAY INVISIBLE (-4625 6775);
FORCEPROP 0 LAST ROOM MIO_CHASSIS
J 0
(-4625 6825);
DISPLAY 1.021277 (-4625 6825);
PAINT ORANGE (-4625 6825);
DISPLAY INVISIBLE (-4625 6825);
FORCEADD P3V3..1
(-5625 5725);
FORCEPROP 3 LASTPIN (-5625 5675) SIG_NAME P3V3\g
J 0
(-5615 5685);
DISPLAY 0.659574 (-5615 5685);
PAINT MONO (-5615 5685);
DISPLAY INVISIBLE (-5615 5685);
FORCEPROP 1 LAST VOLTAGE +3.3
J 0
(-5625 5725);
PAINT SKYBLUE (-5625 5725);
DISPLAY INVISIBLE (-5625 5725);
FORCEPROP 2 LAST CDS_LIB mstr_symbols
J 0
(-5625 5725);
PAINT ORANGE (-5625 5725);
DISPLAY INVISIBLE (-5625 5725);
FORCEPROP 1 LAST SIZE 1B
J 0
(-5580 5747);
DISPLAY 0.553191 (-5580 5747);
PAINT GREEN (-5580 5747);
DISPLAY INVISIBLE (-5580 5747);
FORCEPROP 1 LAST PATH I45
J 0
(-5580 5727);
DISPLAY 0.340426 (-5580 5727);
PAINT GREEN (-5580 5727);
DISPLAY INVISIBLE (-5580 5727);
FORCEPROP 2 LAST ROOM SM_CONTROLLER
J 0
(-6150 5825);
DISPLAY 1.404255 (-6150 5825);
PAINT ORANGE (-6150 5825);
DISPLAY INVISIBLE (-6150 5825);
FORCEPROP 1 LAST BODY_TYPE PLUMBING
J 0
(-5670 5682);
DISPLAY 0.468085 (-5670 5682);
PAINT GREEN (-5670 5682);
DISPLAY INVISIBLE (-5670 5682);
FORCEPROP 1 LAST HDL_POWER P3V3
J 0
(-5950 5600);
DISPLAY 1.170213 (-5950 5600);
PAINT GREEN (-5950 5600);
DISPLAY INVISIBLE (-5950 5600);
FORCEADD GND..1
(-5625 5075);
FORCEPROP 3 LASTPIN (-5625 5125) SIG_NAME GND\g
J 0
(-5615 5135);
DISPLAY 0.659574 (-5615 5135);
PAINT MONO (-5615 5135);
DISPLAY INVISIBLE (-5615 5135);
FORCEPROP 1 LAST VOLTAGE 0
J 0
(-5625 5075);
PAINT SKYBLUE (-5625 5075);
DISPLAY INVISIBLE (-5625 5075);
FORCEPROP 2 LAST CDS_LIB mstr_symbols
J 0
(-5625 5075);
PAINT ORANGE (-5625 5075);
DISPLAY INVISIBLE (-5625 5075);
FORCEPROP 1 LAST SIZE 1B
J 0
(-5550 5025);
DISPLAY 1.212766 (-5550 5025);
PAINT GREEN (-5550 5025);
DISPLAY INVISIBLE (-5550 5025);
FORCEPROP 1 LAST PATH I46
J 0
(-5550 5075);
DISPLAY 0.872340 (-5550 5075);
PAINT AQUA (-5550 5075);
DISPLAY INVISIBLE (-5550 5075);
FORCEPROP 2 LAST ROOM MIO_CHASSIS
J 0
(-6150 5150);
DISPLAY 1.404255 (-6150 5150);
PAINT ORANGE (-6150 5150);
DISPLAY INVISIBLE (-6150 5150);
FORCEPROP 1 LAST BODY_TYPE PLUMBING
J 0
(-5670 5032);
DISPLAY 0.340426 (-5670 5032);
PAINT GREEN (-5670 5032);
DISPLAY INVISIBLE (-5670 5032);
FORCEPROP 1 LAST HDL_POWER GND
J 0
(-5625 5225);
DISPLAY 1.212766 (-5625 5225);
PAINT GREEN (-5625 5225);
DISPLAY INVISIBLE (-5625 5225);
FORCEADD RES..1
(-8100 6325);
FORCEPROP 1 LAST PART_NUMBER G21497-005
J 0
(-8425 6275);
DISPLAY 0.617021 (-8425 6275);
PAINT BLUE (-8425 6275);
FORCEPROP 1 LAST VALUE 0.0
J 2
(-8350 6425);
DISPLAY 0.617021 (-8350 6425);
PAINT SKYBLUE (-8350 6425);
FORCEPROP 1 LAST TOLERANCE 5%
J 0
(-8300 6425);
DISPLAY 0.617021 (-8300 6425);
PAINT SKYBLUE (-8300 6425);
FORCEPROP 1 LAST MATERIAL CHIP
J 0
(-8400 6350);
DISPLAY 0.617021 (-8400 6350);
PAINT SKYBLUE (-8400 6350);
FORCEPROP 1 LASTPIN (-8200 6325) $PN 1
J 0
(-8188 6337);
DISPLAY 0.617021 (-8188 6337);
PAINT MONO (-8188 6337);
FORCEPROP 1 LAST LOCATION R1M10
J 0
(-8175 6375);
DISPLAY 0.617021 (-8175 6375);
PAINT AQUA (-8175 6375);
FORCEPROP 1 LAST PACK_TYPE 0402
J 0
(-7950 6375);
DISPLAY 0.617021 (-7950 6375);
PAINT SKYBLUE (-7950 6375);
FORCEPROP 1 LAST WATTAGE 1/16W
J 2
(-7875 6425);
DISPLAY 0.617021 (-7875 6425);
PAINT SKYBLUE (-7875 6425);
FORCEPROP 1 LASTPIN (-8000 6325) $PN 2
J 0
(-8038 6337);
DISPLAY 0.617021 (-8038 6337);
PAINT MONO (-8038 6337);
FORCEPROP 2 LAST CDS_LIB mstr_discrete
J 0
(-8100 6325);
DISPLAY 1.361702 (-8100 6325);
PAINT ORANGE (-8100 6325);
DISPLAY INVISIBLE (-8100 6325);
FORCEPROP 2 LAST CDS_SEC 1
J 0
(-8150 6525);
DISPLAY 1.404255 (-8150 6525);
PAINT ORANGE (-8150 6525);
DISPLAY INVISIBLE (-8150 6525);
FORCEPROP 2 LAST $SEC 1
J 0
(-8150 6525);
DISPLAY 0.936170 (-8150 6525);
PAINT MONO (-8150 6525);
DISPLAY INVISIBLE (-8150 6525);
FORCEPROP 2 LAST CDS_LOCATION R1M10
J 0
(-8175 6375);
DISPLAY 0.617021 (-8175 6375);
PAINT AQUA (-8175 6375);
DISPLAY INVISIBLE (-8175 6375);
FORCEPROP 1 LAST PATH I6
J 0
(-8150 6475);
DISPLAY 0.978723 (-8150 6475);
PAINT WHITE (-8150 6475);
DISPLAY INVISIBLE (-8150 6475);
FORCEPROP 2 LAST ROOM MIO_CHASSIS
J 0
(-7925 6425);
DISPLAY 1.404255 (-7925 6425);
PAINT ORANGE (-7925 6425);
DISPLAY INVISIBLE (-7925 6425);
FORCEADD TTL1G08..1
(-6550 6275);
FORCEPROP 1 LAST VALUE NC7SZ08
J 1
(-6550 6150);
DISPLAY 0.617021 (-6550 6150);
PAINT SKYBLUE (-6550 6150);
FORCEPROP 2 LASTPIN (-6400 6275) $PN 4
J 0
(-6390 6285);
DISPLAY 0.617021 (-6390 6285);
PAINT ORANGE (-6390 6285);
FORCEPROP 2 LASTPIN (-6700 6225) $PN 2
J 2
(-6710 6235);
DISPLAY 0.617021 (-6710 6235);
PAINT ORANGE (-6710 6235);
FORCEPROP 2 LASTPIN (-6700 6325) $PN 1
J 2
(-6710 6335);
DISPLAY 0.617021 (-6710 6335);
PAINT ORANGE (-6710 6335);
FORCEPROP 1 LAST LOCATION U1M1
J 0
(-6650 6550);
DISPLAY 0.617021 (-6650 6550);
PAINT AQUA (-6650 6550);
FORCEPROP 1 LAST PART_NUMBER D10321-001
J 1
(-6575 6375);
DISPLAY 0.617021 (-6575 6375);
PAINT BLUE (-6575 6375);
FORCEPROP 1 LAST POWER_GROUP VCC=P3V3;GND=GND;
J 1
(-6525 6100);
DISPLAY 0.617021 (-6525 6100);
PAINT ORANGE (-6525 6100);
FORCEPROP 1 LAST PACK_TYPE SOTLF
J 1
(-6575 6450);
DISPLAY 0.617021 (-6575 6450);
PAINT SKYBLUE (-6575 6450);
FORCEPROP 1 LAST MATERIAL IC
J 1
(-6575 6485);
DISPLAY 0.617021 (-6575 6485);
PAINT SKYBLUE (-6575 6485);
FORCEPROP 2 LAST CDS_LIB mstr_ttl
J 0
(-6550 6275);
PAINT MONO (-6550 6275);
DISPLAY INVISIBLE (-6550 6275);
FORCEPROP 2 LAST SEC_TYPE SOTLF
J 0
(-6550 6575);
DISPLAY 1.021277 (-6550 6575);
PAINT ORANGE (-6550 6575);
DISPLAY INVISIBLE (-6550 6575);
FORCEPROP 0 LAST BOM_COST MIO_CHASSIS
J 0
(-6650 6700);
DISPLAY 1.021277 (-6650 6700);
PAINT ORANGE (-6650 6700);
DISPLAY INVISIBLE (-6650 6700);
FORCEPROP 2 LAST SEC 1
J 0
(-6550 6575);
DISPLAY 0.680851 (-6550 6575);
PAINT MONO (-6550 6575);
DISPLAY INVISIBLE (-6550 6575);
FORCEPROP 2 LAST CDS_LOCATION U1M1
J 0
(-6650 6500);
DISPLAY 0.617021 (-6650 6500);
PAINT AQUA (-6650 6500);
DISPLAY INVISIBLE (-6650 6500);
FORCEPROP 1 LAST PATH I70
J 1
(-6570 6540);
DISPLAY 0.702128 (-6570 6540);
PAINT WHITE (-6570 6540);
DISPLAY INVISIBLE (-6570 6540);
FORCEPROP 0 LAST ROOM MIO_CHASSIS
J 0
(-6650 6600);
DISPLAY 1.021277 (-6650 6600);
PAINT ORANGE (-6650 6600);
DISPLAY INVISIBLE (-6650 6600);
FORCEADD LED..2
(-7200 8475);
FORCEPROP 1 LAST LOCATION DS9F1
J 0
(-7100 8525);
DISPLAY 0.617021 (-7100 8525);
PAINT AQUA (-7100 8525);
FORCEPROP 1 LAST PART_NUMBER D14725-005
J 0
(-7100 8375);
DISPLAY 0.617021 (-7100 8375);
PAINT BLUE (-7100 8375);
FORCEPROP 1 LAST MATERIAL IC
J 0
(-7100 8425);
DISPLAY 0.617021 (-7100 8425);
PAINT SKYBLUE (-7100 8425);
FORCEPROP 1 LASTPIN (-7200 8375) $PN 2
J 0
(-7175 8350);
DISPLAY 0.617021 (-7175 8350);
PAINT BLUE (-7175 8350);
FORCEPROP 1 LASTPIN (-7200 8575) $PN 1
J 0
(-7175 8550);
DISPLAY 0.617021 (-7175 8550);
PAINT BLUE (-7175 8550);
FORCEPROP 1 LAST COLOR RED
J 0
(-7100 8475);
DISPLAY 0.617021 (-7100 8475);
PAINT BLUE (-7100 8475);
FORCEPROP 1 LAST PACK_TYPE A1
J 0
(-7100 8325);
DISPLAY 0.978723 (-7100 8325);
PAINT SKYBLUE (-7100 8325);
DISPLAY INVISIBLE (-7100 8325);
FORCEPROP 2 LAST SEC_TYPE A1
J 0
(-7100 8625);
DISPLAY 1.021277 (-7100 8625);
PAINT ORANGE (-7100 8625);
DISPLAY INVISIBLE (-7100 8625);
FORCEPROP 2 LAST CDS_LIB mstr_discrete
J 0
(-7200 8475);
PAINT ORANGE (-7200 8475);
DISPLAY INVISIBLE (-7200 8475);
FORCEPROP 0 LAST BOM_COST SM_CONTROLLER
J 0
(-7100 8725);
DISPLAY 1.021277 (-7100 8725);
PAINT ORANGE (-7100 8725);
DISPLAY INVISIBLE (-7100 8725);
FORCEPROP 2 LAST SEC 1
J 0
(-7100 8625);
DISPLAY 0.680851 (-7100 8625);
PAINT MONO (-7100 8625);
DISPLAY INVISIBLE (-7100 8625);
FORCEPROP 2 LAST CDS_LOCATION DS9F1
J 0
(-7100 8525);
DISPLAY 0.617021 (-7100 8525);
PAINT AQUA (-7100 8525);
DISPLAY INVISIBLE (-7100 8525);
FORCEPROP 1 LAST PATH I71
J 0
(-7100 8575);
DISPLAY 0.978723 (-7100 8575);
PAINT BLUE (-7100 8575);
DISPLAY INVISIBLE (-7100 8575);
FORCEPROP 0 LAST ROOM BMC
J 0
(-7100 8625);
DISPLAY 1.021277 (-7100 8625);
PAINT ORANGE (-7100 8625);
DISPLAY INVISIBLE (-7100 8625);
FORCEADD RES..2
(-7200 8825);
FORCEPROP 1 LAST LOCATION R9F28
J 0
(-7155 8950);
DISPLAY 0.617021 (-7155 8950);
PAINT AQUA (-7155 8950);
FORCEPROP 1 LAST PART_NUMBER G21796-271
J 0
(-7160 8700);
DISPLAY 0.617021 (-7160 8700);
PAINT BLUE (-7160 8700);
FORCEPROP 1 LAST VALUE 221
J 0
(-7155 8900);
DISPLAY 0.617021 (-7155 8900);
PAINT SKYBLUE (-7155 8900);
FORCEPROP 1 LAST TOLERANCE 1.0%
J 0
(-7155 8850);
DISPLAY 0.617021 (-7155 8850);
PAINT SKYBLUE (-7155 8850);
FORCEPROP 1 LAST PACK_TYPE 0402
J 0
(-7160 8650);
DISPLAY 0.617021 (-7160 8650);
PAINT SKYBLUE (-7160 8650);
FORCEPROP 1 LAST MATERIAL CHIP
J 0
(-7160 8750);
DISPLAY 0.617021 (-7160 8750);
PAINT SKYBLUE (-7160 8750);
FORCEPROP 1 LAST WATTAGE 1/16W
J 0
(-7160 8800);
DISPLAY 0.617021 (-7160 8800);
PAINT SKYBLUE (-7160 8800);
FORCEPROP 1 LASTPIN (-7200 8725) $PN 2
J 0
(-7195 8735);
DISPLAY 0.617021 (-7195 8735);
PAINT ORANGE (-7195 8735);
FORCEPROP 1 LASTPIN (-7200 8925) $PN 1
J 0
(-7195 8887);
DISPLAY 0.617021 (-7195 8887);
PAINT ORANGE (-7195 8887);
FORCEPROP 2 LAST SEC_TYPE 0402
J 0
(-7150 9050);
DISPLAY 1.021277 (-7150 9050);
PAINT ORANGE (-7150 9050);
DISPLAY INVISIBLE (-7150 9050);
FORCEPROP 2 LAST CDS_LIB mstr_discrete
J 0
(-7200 8825);
PAINT MONO (-7200 8825);
DISPLAY INVISIBLE (-7200 8825);
FORCEPROP 0 LAST BOM_COST SM_CONTROLLER
J 0
(-7150 9150);
DISPLAY 1.021277 (-7150 9150);
PAINT ORANGE (-7150 9150);
DISPLAY INVISIBLE (-7150 9150);
FORCEPROP 2 LAST SEC 1
J 0
(-7150 9050);
DISPLAY 0.680851 (-7150 9050);
PAINT MONO (-7150 9050);
DISPLAY INVISIBLE (-7150 9050);
FORCEPROP 2 LAST CDS_LOCATION R9F28
J 0
(-7155 8950);
DISPLAY 0.617021 (-7155 8950);
PAINT AQUA (-7155 8950);
DISPLAY INVISIBLE (-7155 8950);
FORCEPROP 1 LAST PATH I72
J 0
(-7150 9000);
DISPLAY 0.978723 (-7150 9000);
PAINT WHITE (-7150 9000);
DISPLAY INVISIBLE (-7150 9000);
FORCEPROP 0 LAST ROOM BMC
J 0
(-7150 9050);
DISPLAY 1.021277 (-7150 9050);
PAINT ORANGE (-7150 9050);
DISPLAY INVISIBLE (-7150 9050);
FORCEADD GND..1
(-7200 7650);
FORCEPROP 3 LASTPIN (-7200 7700) SIG_NAME GND\g
J 0
(-7190 7710);
DISPLAY 0.659574 (-7190 7710);
PAINT MONO (-7190 7710);
DISPLAY INVISIBLE (-7190 7710);
FORCEPROP 1 LAST VOLTAGE 0.0V
J 0
(-7245 7607);
DISPLAY 0.340426 (-7245 7607);
PAINT SKYBLUE (-7245 7607);
DISPLAY INVISIBLE (-7245 7607);
FORCEPROP 1 LAST SIZE 1B
J 0
(-7125 7600);
DISPLAY 0.872340 (-7125 7600);
PAINT AQUA (-7125 7600);
DISPLAY INVISIBLE (-7125 7600);
FORCEPROP 2 LAST CDS_LIB mstr_symbols
J 0
(-7200 7650);
PAINT MONO (-7200 7650);
DISPLAY INVISIBLE (-7200 7650);
FORCEPROP 1 LAST PATH I74
J 0
(-7125 7650);
DISPLAY 0.872340 (-7125 7650);
PAINT AQUA (-7125 7650);
DISPLAY INVISIBLE (-7125 7650);
FORCEPROP 1 LAST BODY_TYPE PLUMBING
J 0
(-7245 7607);
DISPLAY 0.340426 (-7245 7607);
PAINT GREEN (-7245 7607);
DISPLAY INVISIBLE (-7245 7607);
FORCEPROP 1 LAST HDL_POWER GND
J 0
(-7200 7800);
DISPLAY 0.872340 (-7200 7800);
PAINT GREEN (-7200 7800);
DISPLAY INVISIBLE (-7200 7800);
FORCEADD RES..2
(-8800 7850);
FORCEPROP 1 LAST PART_NUMBER G21796-072
J 0
(-8760 7725);
DISPLAY 0.617021 (-8760 7725);
PAINT BLUE (-8760 7725);
FORCEPROP 1 LASTPIN (-8800 7950) $PN 1
J 0
(-8795 7912);
DISPLAY 0.617021 (-8795 7912);
PAINT ORANGE (-8795 7912);
FORCEPROP 1 LASTPIN (-8800 7750) $PN 2
J 0
(-8795 7760);
DISPLAY 0.617021 (-8795 7760);
PAINT ORANGE (-8795 7760);
FORCEPROP 1 LAST WATTAGE 1/16W
J 0
(-8760 7825);
DISPLAY 0.617021 (-8760 7825);
PAINT SKYBLUE (-8760 7825);
FORCEPROP 1 LAST MATERIAL CHIP
J 0
(-8760 7775);
DISPLAY 0.617021 (-8760 7775);
PAINT SKYBLUE (-8760 7775);
FORCEPROP 1 LAST PACK_TYPE 0402
J 0
(-8760 7675);
DISPLAY 0.617021 (-8760 7675);
PAINT SKYBLUE (-8760 7675);
FORCEPROP 1 LAST TOLERANCE 1%
J 0
(-8755 7875);
DISPLAY 0.617021 (-8755 7875);
PAINT SKYBLUE (-8755 7875);
FORCEPROP 1 LAST VALUE 4.75K
J 0
(-8755 7925);
DISPLAY 0.617021 (-8755 7925);
PAINT SKYBLUE (-8755 7925);
FORCEPROP 1 LAST LOCATION R9F30
J 0
(-8755 7975);
DISPLAY 0.617021 (-8755 7975);
PAINT AQUA (-8755 7975);
FORCEPROP 0 LAST ROOM BMC
J 0
(-8750 8075);
DISPLAY 1.021277 (-8750 8075);
PAINT ORANGE (-8750 8075);
DISPLAY INVISIBLE (-8750 8075);
FORCEPROP 1 LAST PATH I76
J 0
(-8750 8025);
DISPLAY 0.978723 (-8750 8025);
PAINT WHITE (-8750 8025);
DISPLAY INVISIBLE (-8750 8025);
FORCEPROP 2 LAST CDS_LOCATION R9F30
J 0
(-8755 7975);
DISPLAY 0.617021 (-8755 7975);
PAINT AQUA (-8755 7975);
DISPLAY INVISIBLE (-8755 7975);
FORCEPROP 2 LAST SEC 1
J 0
(-8750 8075);
DISPLAY 0.680851 (-8750 8075);
PAINT MONO (-8750 8075);
DISPLAY INVISIBLE (-8750 8075);
FORCEPROP 2 LAST SEC_TYPE 0402
J 0
(-8750 8075);
DISPLAY 1.021277 (-8750 8075);
PAINT ORANGE (-8750 8075);
DISPLAY INVISIBLE (-8750 8075);
FORCEPROP 2 LAST CDS_LIB mstr_discrete
J 0
(-8800 7850);
PAINT MONO (-8800 7850);
DISPLAY INVISIBLE (-8800 7850);
FORCEPROP 0 LAST BOM_COST SM_CONTROLLER
J 0
(-8750 8175);
DISPLAY 1.021277 (-8750 8175);
PAINT ORANGE (-8750 8175);
DISPLAY INVISIBLE (-8750 8175);
FORCEADD P3V3_STBY..1
(-8800 8125);
FORCEPROP 3 LASTPIN (-8800 8075) SIG_NAME P3V3_STBY\g
J 0
(-8790 8085);
DISPLAY 0.659574 (-8790 8085);
PAINT MONO (-8790 8085);
DISPLAY INVISIBLE (-8790 8085);
FORCEPROP 1 LAST HDL_POWER P3V3_STBY
J 0
(-9100 8000);
DISPLAY 0.872340 (-9100 8000);
PAINT ORANGE (-9100 8000);
DISPLAY INVISIBLE (-9100 8000);
FORCEPROP 1 LAST BODY_TYPE PLUMBING
J 0
(-8845 8082);
DISPLAY 0.340426 (-8845 8082);
PAINT GREEN (-8845 8082);
DISPLAY INVISIBLE (-8845 8082);
FORCEPROP 1 LAST PATH I77
J 0
(-8755 8127);
DISPLAY 0.340426 (-8755 8127);
PAINT GREEN (-8755 8127);
DISPLAY INVISIBLE (-8755 8127);
FORCEPROP 1 LAST SIZE 1B
J 0
(-8755 8147);
DISPLAY 0.340426 (-8755 8147);
PAINT GREEN (-8755 8147);
DISPLAY INVISIBLE (-8755 8147);
FORCEPROP 2 LAST CDS_LIB mstr_symbols
J 0
(-8800 8125);
PAINT MONO (-8800 8125);
DISPLAY INVISIBLE (-8800 8125);
FORCEPROP 1 LAST VOLTAGE 3.3V
J 0
(-8845 8082);
DISPLAY 0.340426 (-8845 8082);
PAINT SKYBLUE (-8845 8082);
DISPLAY INVISIBLE (-8845 8082);
FORCEADD P3V3_STBY..1
(-7200 9125);
FORCEPROP 3 LASTPIN (-7200 9075) SIG_NAME P3V3_STBY\g
J 0
(-7190 9085);
DISPLAY 0.659574 (-7190 9085);
PAINT MONO (-7190 9085);
DISPLAY INVISIBLE (-7190 9085);
FORCEPROP 1 LAST VOLTAGE 3.3V
J 0
(-7245 9082);
DISPLAY 0.340426 (-7245 9082);
PAINT SKYBLUE (-7245 9082);
DISPLAY INVISIBLE (-7245 9082);
FORCEPROP 1 LAST SIZE 1B
J 0
(-7155 9147);
DISPLAY 0.340426 (-7155 9147);
PAINT GREEN (-7155 9147);
DISPLAY INVISIBLE (-7155 9147);
FORCEPROP 2 LAST CDS_LIB mstr_symbols
J 0
(-7200 9125);
PAINT MONO (-7200 9125);
DISPLAY INVISIBLE (-7200 9125);
FORCEPROP 1 LAST PATH I78
J 0
(-7155 9127);
DISPLAY 0.340426 (-7155 9127);
PAINT GREEN (-7155 9127);
DISPLAY INVISIBLE (-7155 9127);
FORCEPROP 1 LAST BODY_TYPE PLUMBING
J 0
(-7245 9082);
DISPLAY 0.340426 (-7245 9082);
PAINT GREEN (-7245 9082);
DISPLAY INVISIBLE (-7245 9082);
FORCEPROP 1 LAST HDL_POWER P3V3_STBY
J 0
(-7500 9000);
DISPLAY 0.872340 (-7500 9000);
PAINT ORANGE (-7500 9000);
DISPLAY INVISIBLE (-7500 9000);
FORCEADD FET_N_DUAL..5
(-7200 8050);
FORCEPROP 1 LAST LOCATION Q9F1
J 0
(-7000 8050);
DISPLAY 0.617021 (-7000 8050);
PAINT AQUA (-7000 8050);
FORCEPROP 1 LAST PART_NUMBER E40049-001
J 0
(-7000 7850);
DISPLAY 0.617021 (-7000 7850);
PAINT BLUE (-7000 7850);
FORCEPROP 1 LAST VALUE NTJD4001N
J 0
(-7000 8000);
DISPLAY 0.617021 (-7000 8000);
PAINT SKYBLUE (-7000 8000);
FORCEPROP 1 LAST MATERIAL FET
J 0
(-7000 7950);
DISPLAY 0.617021 (-7000 7950);
PAINT SKYBLUE (-7000 7950);
FORCEPROP 1 LASTPIN (-7200 7850) $PN 4
J 2
(-7142 7850);
DISPLAY 0.617021 (-7142 7850);
PAINT WHITE (-7142 7850);
FORCEPROP 1 LASTPIN (-7400 7950) $PN 5
J 2
(-7397 7965);
DISPLAY 0.617021 (-7397 7965);
PAINT WHITE (-7397 7965);
FORCEPROP 1 LASTPIN (-7200 8250) $PN 3
J 2
(-7147 8215);
DISPLAY 0.617021 (-7147 8215);
PAINT WHITE (-7147 8215);
FORCEPROP 1 LAST PACK_TYPE SMLF
J 0
(-7000 7900);
DISPLAY 0.978723 (-7000 7900);
PAINT SKYBLUE (-7000 7900);
DISPLAY INVISIBLE (-7000 7900);
FORCEPROP 2 LAST CDS_LIB mstr_discrete
J 0
(-7200 8050);
PAINT MONO (-7200 8050);
DISPLAY INVISIBLE (-7200 8050);
FORCEPROP 0 LAST BOM_COST SM_CONTROLLER
J 0
(-7000 8250);
DISPLAY 1.021277 (-7000 8250);
PAINT ORANGE (-7000 8250);
DISPLAY INVISIBLE (-7000 8250);
FORCEPROP 2 LAST SEC_TYPE SMLF
J 0
(-7000 8150);
DISPLAY 1.021277 (-7000 8150);
PAINT ORANGE (-7000 8150);
DISPLAY INVISIBLE (-7000 8150);
FORCEPROP 2 LAST SEC 2
J 0
(-7000 8150);
DISPLAY 0.680851 (-7000 8150);
PAINT MONO (-7000 8150);
DISPLAY INVISIBLE (-7000 8150);
FORCEPROP 2 LAST CDS_LOCATION Q9F1
J 0
(-7000 8050);
DISPLAY 0.617021 (-7000 8050);
PAINT AQUA (-7000 8050);
DISPLAY INVISIBLE (-7000 8050);
FORCEPROP 1 LAST PATH I79
J 0
(-7000 8100);
DISPLAY 0.978723 (-7000 8100);
PAINT BLUE (-7000 8100);
DISPLAY INVISIBLE (-7000 8100);
FORCEPROP 0 LAST ROOM BMC
J 0
(-7000 8150);
DISPLAY 1.021277 (-7000 8150);
PAINT ORANGE (-7000 8150);
DISPLAY INVISIBLE (-7000 8150);
FORCEADD RES..2
(-6975 6550);
FORCEPROP 1 LAST LOCATION R1M12
J 0
(-6930 6675);
DISPLAY 0.617021 (-6930 6675);
PAINT AQUA (-6930 6675);
FORCEPROP 1 LAST VALUE 10.0K
J 0
(-6930 6625);
DISPLAY 0.617021 (-6930 6625);
PAINT SKYBLUE (-6930 6625);
FORCEPROP 1 LAST TOLERANCE 1%
J 0
(-6930 6575);
DISPLAY 0.617021 (-6930 6575);
PAINT SKYBLUE (-6930 6575);
FORCEPROP 1 LAST WATTAGE 1/16W
J 0
(-6935 6525);
DISPLAY 0.617021 (-6935 6525);
PAINT SKYBLUE (-6935 6525);
FORCEPROP 1 LASTPIN (-6975 6450) $PN 2
J 0
(-6970 6460);
DISPLAY 0.617021 (-6970 6460);
PAINT MONO (-6970 6460);
FORCEPROP 1 LASTPIN (-6975 6650) $PN 1
J 0
(-6970 6612);
DISPLAY 0.617021 (-6970 6612);
PAINT MONO (-6970 6612);
FORCEPROP 1 LAST MATERIAL CHIP
J 0
(-6935 6475);
DISPLAY 0.617021 (-6935 6475);
PAINT SKYBLUE (-6935 6475);
FORCEPROP 1 LAST PACK_TYPE 0402
J 0
(-6935 6375);
DISPLAY 0.617021 (-6935 6375);
PAINT SKYBLUE (-6935 6375);
FORCEPROP 1 LAST PART_NUMBER G21796-016
J 0
(-6935 6425);
DISPLAY 0.617021 (-6935 6425);
PAINT BLUE (-6935 6425);
FORCEPROP 2 LAST SEC_TYPE 0402
J 0
(-6925 6775);
DISPLAY 1.361702 (-6925 6775);
PAINT MONO (-6925 6775);
DISPLAY INVISIBLE (-6925 6775);
FORCEPROP 2 LAST CDS_LIB mstr_discrete
J 0
(-6975 6550);
DISPLAY 1.361702 (-6975 6550);
PAINT ORANGE (-6975 6550);
DISPLAY INVISIBLE (-6975 6550);
FORCEPROP 2 LAST SEC 1
J 0
(-6925 6775);
DISPLAY 0.936170 (-6925 6775);
PAINT MONO (-6925 6775);
DISPLAY INVISIBLE (-6925 6775);
FORCEPROP 2 LAST CDS_LOCATION R1M12
J 0
(-6930 6675);
DISPLAY 0.617021 (-6930 6675);
PAINT AQUA (-6930 6675);
DISPLAY INVISIBLE (-6930 6675);
FORCEPROP 1 LAST PATH I8
J 0
(-6925 6725);
DISPLAY 0.978723 (-6925 6725);
PAINT WHITE (-6925 6725);
DISPLAY INVISIBLE (-6925 6725);
FORCEPROP 2 LAST ROOM MIO_CHASSIS
J 0
(-6925 6725);
DISPLAY 1.404255 (-6925 6725);
PAINT ORANGE (-6925 6725);
DISPLAY INVISIBLE (-6925 6725);
FORCEADD FET_N_DUAL..5
(-8125 7675);
FORCEPROP 1 LASTPIN (-8125 7875) $PN 6
J 2
(-8072 7840);
DISPLAY 0.617021 (-8072 7840);
PAINT WHITE (-8072 7840);
FORCEPROP 1 LASTPIN (-8325 7575) $PN 2
J 2
(-8322 7590);
DISPLAY 0.617021 (-8322 7590);
PAINT WHITE (-8322 7590);
FORCEPROP 1 LASTPIN (-8125 7475) $PN 1
J 2
(-8067 7475);
DISPLAY 0.617021 (-8067 7475);
PAINT WHITE (-8067 7475);
FORCEPROP 1 LAST MATERIAL FET
J 0
(-7925 7575);
DISPLAY 0.617021 (-7925 7575);
PAINT SKYBLUE (-7925 7575);
FORCEPROP 1 LAST VALUE NTJD4001N
J 0
(-7925 7625);
DISPLAY 0.617021 (-7925 7625);
PAINT SKYBLUE (-7925 7625);
FORCEPROP 1 LAST PART_NUMBER E40049-001
J 0
(-7925 7475);
DISPLAY 0.617021 (-7925 7475);
PAINT BLUE (-7925 7475);
FORCEPROP 1 LAST LOCATION Q9F1
J 0
(-7925 7675);
DISPLAY 0.617021 (-7925 7675);
PAINT AQUA (-7925 7675);
FORCEPROP 0 LAST ROOM BMC
J 0
(-7925 7775);
DISPLAY 1.021277 (-7925 7775);
PAINT ORANGE (-7925 7775);
DISPLAY INVISIBLE (-7925 7775);
FORCEPROP 1 LAST PATH I80
J 0
(-7925 7725);
DISPLAY 0.978723 (-7925 7725);
PAINT BLUE (-7925 7725);
DISPLAY INVISIBLE (-7925 7725);
FORCEPROP 2 LAST CDS_LOCATION Q9F1
J 0
(-7925 7675);
DISPLAY 0.617021 (-7925 7675);
PAINT AQUA (-7925 7675);
DISPLAY INVISIBLE (-7925 7675);
FORCEPROP 2 LAST SEC 1
J 0
(-7925 7775);
DISPLAY 0.680851 (-7925 7775);
PAINT MONO (-7925 7775);
DISPLAY INVISIBLE (-7925 7775);
FORCEPROP 0 LAST BOM_COST SM_CONTROLLER
J 0
(-7925 7875);
DISPLAY 1.021277 (-7925 7875);
PAINT ORANGE (-7925 7875);
DISPLAY INVISIBLE (-7925 7875);
FORCEPROP 2 LAST SEC_TYPE SMLF
J 0
(-7925 7775);
DISPLAY 1.021277 (-7925 7775);
PAINT ORANGE (-7925 7775);
DISPLAY INVISIBLE (-7925 7775);
FORCEPROP 2 LAST CDS_LIB mstr_discrete
J 0
(-8125 7675);
PAINT MONO (-8125 7675);
DISPLAY INVISIBLE (-8125 7675);
FORCEPROP 1 LAST PACK_TYPE SMLF
J 0
(-7925 7525);
DISPLAY 0.978723 (-7925 7525);
PAINT SKYBLUE (-7925 7525);
DISPLAY INVISIBLE (-7925 7525);
FORCEADD P3V3_STBY..1
(-8125 8500);
FORCEPROP 3 LASTPIN (-8125 8450) SIG_NAME P3V3_STBY\g
J 0
(-8115 8460);
DISPLAY 0.659574 (-8115 8460);
PAINT MONO (-8115 8460);
DISPLAY INVISIBLE (-8115 8460);
FORCEPROP 1 LAST HDL_POWER P3V3_STBY
J 0
(-8425 8375);
DISPLAY 0.872340 (-8425 8375);
PAINT ORANGE (-8425 8375);
DISPLAY INVISIBLE (-8425 8375);
FORCEPROP 1 LAST BODY_TYPE PLUMBING
J 0
(-8170 8457);
DISPLAY 0.340426 (-8170 8457);
PAINT GREEN (-8170 8457);
DISPLAY INVISIBLE (-8170 8457);
FORCEPROP 1 LAST PATH I81
J 0
(-8080 8502);
DISPLAY 0.340426 (-8080 8502);
PAINT GREEN (-8080 8502);
DISPLAY INVISIBLE (-8080 8502);
FORCEPROP 2 LAST CDS_LIB mstr_symbols
J 0
(-8125 8500);
PAINT MONO (-8125 8500);
DISPLAY INVISIBLE (-8125 8500);
FORCEPROP 1 LAST SIZE 1B
J 0
(-8080 8522);
DISPLAY 0.340426 (-8080 8522);
PAINT GREEN (-8080 8522);
DISPLAY INVISIBLE (-8080 8522);
FORCEPROP 1 LAST VOLTAGE 3.3V
J 0
(-8170 8457);
DISPLAY 0.340426 (-8170 8457);
PAINT SKYBLUE (-8170 8457);
DISPLAY INVISIBLE (-8170 8457);
FORCEADD RES..2
(-8125 8225);
FORCEPROP 1 LASTPIN (-8125 8325) $PN 1
J 0
(-8120 8287);
DISPLAY 0.617021 (-8120 8287);
PAINT ORANGE (-8120 8287);
FORCEPROP 1 LASTPIN (-8125 8125) $PN 2
J 0
(-8120 8135);
DISPLAY 0.617021 (-8120 8135);
PAINT ORANGE (-8120 8135);
FORCEPROP 1 LAST WATTAGE 1/16W
J 0
(-8085 8200);
DISPLAY 0.617021 (-8085 8200);
PAINT SKYBLUE (-8085 8200);
FORCEPROP 1 LAST MATERIAL CHIP
J 0
(-8085 8150);
DISPLAY 0.617021 (-8085 8150);
PAINT SKYBLUE (-8085 8150);
FORCEPROP 1 LAST PACK_TYPE 0402
J 0
(-8085 8050);
DISPLAY 0.617021 (-8085 8050);
PAINT SKYBLUE (-8085 8050);
FORCEPROP 1 LAST TOLERANCE 1%
J 0
(-8080 8250);
DISPLAY 0.617021 (-8080 8250);
PAINT SKYBLUE (-8080 8250);
FORCEPROP 1 LAST VALUE 4.75K
J 0
(-8080 8300);
DISPLAY 0.617021 (-8080 8300);
PAINT SKYBLUE (-8080 8300);
FORCEPROP 1 LAST PART_NUMBER G21796-072
J 0
(-8085 8100);
DISPLAY 0.617021 (-8085 8100);
PAINT BLUE (-8085 8100);
FORCEPROP 1 LAST LOCATION R9F52
J 0
(-8080 8350);
DISPLAY 0.617021 (-8080 8350);
PAINT AQUA (-8080 8350);
FORCEPROP 0 LAST ROOM BMC
J 0
(-8075 8450);
DISPLAY 1.021277 (-8075 8450);
PAINT ORANGE (-8075 8450);
DISPLAY INVISIBLE (-8075 8450);
FORCEPROP 1 LAST PATH I82
J 0
(-8075 8400);
DISPLAY 0.978723 (-8075 8400);
PAINT WHITE (-8075 8400);
DISPLAY INVISIBLE (-8075 8400);
FORCEPROP 2 LAST CDS_LOCATION R9F52
J 0
(-8080 8350);
DISPLAY 0.617021 (-8080 8350);
PAINT AQUA (-8080 8350);
DISPLAY INVISIBLE (-8080 8350);
FORCEPROP 2 LAST SEC 1
J 0
(-8075 8450);
DISPLAY 0.680851 (-8075 8450);
PAINT MONO (-8075 8450);
DISPLAY INVISIBLE (-8075 8450);
FORCEPROP 0 LAST BOM_COST SM_CONTROLLER
J 0
(-8075 8550);
DISPLAY 1.021277 (-8075 8550);
PAINT ORANGE (-8075 8550);
DISPLAY INVISIBLE (-8075 8550);
FORCEPROP 2 LAST CDS_LIB mstr_discrete
J 0
(-8125 8225);
PAINT MONO (-8125 8225);
DISPLAY INVISIBLE (-8125 8225);
FORCEPROP 2 LAST SEC_TYPE 0402
J 0
(-8075 8450);
DISPLAY 1.021277 (-8075 8450);
PAINT ORANGE (-8075 8450);
DISPLAY INVISIBLE (-8075 8450);
FORCEADD GND..1
(-8125 7325);
FORCEPROP 3 LASTPIN (-8125 7375) SIG_NAME GND\g
J 0
(-8115 7385);
DISPLAY 0.659574 (-8115 7385);
PAINT MONO (-8115 7385);
DISPLAY INVISIBLE (-8115 7385);
FORCEPROP 1 LAST HDL_POWER GND
J 0
(-8125 7475);
DISPLAY 0.872340 (-8125 7475);
PAINT GREEN (-8125 7475);
DISPLAY INVISIBLE (-8125 7475);
FORCEPROP 1 LAST BODY_TYPE PLUMBING
J 0
(-8170 7282);
DISPLAY 0.340426 (-8170 7282);
PAINT GREEN (-8170 7282);
DISPLAY INVISIBLE (-8170 7282);
FORCEPROP 1 LAST PATH I83
J 0
(-8050 7325);
DISPLAY 0.872340 (-8050 7325);
PAINT AQUA (-8050 7325);
DISPLAY INVISIBLE (-8050 7325);
FORCEPROP 1 LAST SIZE 1B
J 0
(-8050 7275);
DISPLAY 0.872340 (-8050 7275);
PAINT AQUA (-8050 7275);
DISPLAY INVISIBLE (-8050 7275);
FORCEPROP 2 LAST CDS_LIB mstr_symbols
J 0
(-8125 7325);
PAINT MONO (-8125 7325);
DISPLAY INVISIBLE (-8125 7325);
FORCEPROP 1 LAST VOLTAGE 0.0V
J 0
(-8170 7282);
DISPLAY 0.340426 (-8170 7282);
PAINT SKYBLUE (-8170 7282);
DISPLAY INVISIBLE (-8170 7282);
FORCEADD OFFPAGE..1
(-9075 7575);
FORCEPROP 2 LAST $XR1 147 
J 0
(-9447 7575);
DISPLAY 0.638298 (-9447 7575);
PAINT MONO (-9447 7575);
FORCEPROP 2 LAST $XR0 119 
J 0
(-9327 7575);
DISPLAY 0.638298 (-9327 7575);
PAINT MONO (-9327 7575);
FORCEPROP 1 LAST COMMENT_BODY TRUE
J 0
(-8950 7475);
DISPLAY 0.872340 (-8950 7475);
PAINT GREEN (-8950 7475);
DISPLAY INVISIBLE (-8950 7475);
FORCEPROP 1 LAST OFFPAGE TRUE
J 0
(-8750 7450);
DISPLAY 0.872340 (-8750 7450);
PAINT GREEN (-8750 7450);
DISPLAY INVISIBLE (-8750 7450);
FORCEPROP 2 LAST PATH I84
J 0
(-9025 7650);
DISPLAY 1.021277 (-9025 7650);
PAINT ORANGE (-9025 7650);
DISPLAY INVISIBLE (-9025 7650);
FORCEPROP 2 LAST CDS_LIB mstr_standard
J 0
(-9075 7575);
PAINT MONO (-9075 7575);
DISPLAY INVISIBLE (-9075 7575);
FORCEADD P3V3..1
(-4675 6925);
FORCEPROP 3 LASTPIN (-4675 6875) SIG_NAME P3V3\g
J 0
(-4665 6885);
DISPLAY 0.659574 (-4665 6885);
PAINT MONO (-4665 6885);
DISPLAY INVISIBLE (-4665 6885);
FORCEPROP 1 LAST VOLTAGE 3.3V
J 0
(-4720 6882);
DISPLAY 0.340426 (-4720 6882);
PAINT SKYBLUE (-4720 6882);
DISPLAY INVISIBLE (-4720 6882);
FORCEPROP 2 LAST CDS_LIB mstr_symbols
J 0
(-4675 6925);
PAINT MONO (-4675 6925);
DISPLAY INVISIBLE (-4675 6925);
FORCEPROP 1 LAST SIZE 1B
J 0
(-4630 6947);
DISPLAY 0.340426 (-4630 6947);
PAINT GREEN (-4630 6947);
DISPLAY INVISIBLE (-4630 6947);
FORCEPROP 1 LAST PATH I85
J 0
(-4630 6927);
DISPLAY 0.340426 (-4630 6927);
PAINT GREEN (-4630 6927);
DISPLAY INVISIBLE (-4630 6927);
FORCEPROP 1 LAST BODY_TYPE PLUMBING
J 0
(-4720 6882);
DISPLAY 0.340426 (-4720 6882);
PAINT GREEN (-4720 6882);
DISPLAY INVISIBLE (-4720 6882);
FORCEPROP 1 LAST HDL_POWER P3V3
J 0
(-5000 6800);
DISPLAY 0.872340 (-5000 6800);
PAINT ORANGE (-5000 6800);
DISPLAY INVISIBLE (-5000 6800);
FORCEADD RES..2
R 2
(-7025 6550);
FORCEPROP 1 LAST PART_NUMBER G21796-016
J 2
(-7040 6425);
DISPLAY 0.617021 (-7040 6425);
PAINT BLUE (-7040 6425);
FORCEPROP 1 LAST TOLERANCE 1%
J 2
(-7070 6575);
DISPLAY 0.617021 (-7070 6575);
PAINT SKYBLUE (-7070 6575);
FORCEPROP 1 LAST MATERIAL CHIP
J 2
(-7065 6475);
DISPLAY 0.617021 (-7065 6475);
PAINT SKYBLUE (-7065 6475);
FORCEPROP 1 LASTPIN (-7025 6450) $PN 2
J 2
(-7030 6460);
DISPLAY 0.617021 (-7030 6460);
PAINT MONO (-7030 6460);
FORCEPROP 1 LASTPIN (-7025 6650) $PN 1
J 2
(-7030 6612);
DISPLAY 0.617021 (-7030 6612);
PAINT MONO (-7030 6612);
FORCEPROP 1 LAST PACK_TYPE 0402
J 2
(-7065 6375);
DISPLAY 0.617021 (-7065 6375);
PAINT SKYBLUE (-7065 6375);
FORCEPROP 1 LAST LOCATION R1M11
J 2
(-7070 6675);
DISPLAY 0.617021 (-7070 6675);
PAINT AQUA (-7070 6675);
FORCEPROP 1 LAST VALUE 10.0K
J 2
(-7070 6625);
DISPLAY 0.617021 (-7070 6625);
PAINT SKYBLUE (-7070 6625);
FORCEPROP 1 LAST WATTAGE 1/16W
J 2
(-7065 6525);
DISPLAY 0.617021 (-7065 6525);
PAINT SKYBLUE (-7065 6525);
FORCEPROP 2 LAST SEC_TYPE 0402
J 2
(-7075 6775);
DISPLAY 1.361702 (-7075 6775);
PAINT MONO (-7075 6775);
DISPLAY INVISIBLE (-7075 6775);
FORCEPROP 2 LAST CDS_LIB mstr_discrete
J 2
(-7025 6550);
DISPLAY 1.361702 (-7025 6550);
PAINT ORANGE (-7025 6550);
DISPLAY INVISIBLE (-7025 6550);
FORCEPROP 2 LAST SEC 1
J 2
(-7075 6775);
DISPLAY 0.936170 (-7075 6775);
PAINT MONO (-7075 6775);
DISPLAY INVISIBLE (-7075 6775);
FORCEPROP 2 LAST CDS_LOCATION R1M11
J 2
(-7070 6675);
DISPLAY 0.617021 (-7070 6675);
PAINT AQUA (-7070 6675);
DISPLAY INVISIBLE (-7070 6675);
FORCEPROP 1 LAST PATH I9
J 2
(-7075 6725);
DISPLAY 0.978723 (-7075 6725);
PAINT WHITE (-7075 6725);
DISPLAY INVISIBLE (-7075 6725);
FORCEPROP 2 LAST ROOM MIO_CHASSIS
J 2
(-7075 6725);
DISPLAY 1.404255 (-7075 6725);
PAINT ORANGE (-7075 6725);
DISPLAY INVISIBLE (-7075 6725);
FORCEADD CAD_NOTE..1
(-6425 8725);
FORCEPROP 0 LAST L1 PLEASE PLACE LED NEAR BMC
J 0
(-6575 8600);
DISPLAY 1.021277 (-6575 8600);
PAINT ORANGE (-6575 8600);
FORCEPROP 2 LAST CDS_LIB mstr_symbols
J 0
(-6425 8725);
PAINT MONO (-6425 8725);
DISPLAY INVISIBLE (-6425 8725);
FORCEPROP 1 LAST COMMENT_BODY TRUE
J 0
(-6400 8825);
DISPLAY 0.978723 (-6400 8825);
PAINT ORANGE (-6400 8825);
DISPLAY INVISIBLE (-6400 8825);
FORCEADD INTEL_CORP_BPAGE..1
(-2175 4550);
FORCEPROP 1 LAST CDS_CON_LAST_MODIFIED Fri Jun 16 17:49:06 2017
J 0
(-3600 4875);
PAINT ORANGE (-3600 4875);
DISPLAY INVISIBLE (-3600 4875);
FORCEPROP 1 LAST CUSTOM_TXT_CDS <CURRENT_DESIGN_SHEET> OF <TOTAL_DESIGN_SHEETS>
J 0
(-2675 4575);
PAINT ORANGE (-2675 4575);
FORCEPROP 1 LAST CUSTOM_TXT_CDS <CON_LAST_MODIFIED>
J 0
(-6175 4650);
PAINT ORANGE (-6175 4650);
FORCEPROP 2 LAST CUSTOM_TXT_CDS <XR_PAGE_TITLE>
J 0
(-10065 9800);
DISPLAY 0.638298 (-10065 9800);
PAINT PINK (-10065 9800);
DISPLAY INVISIBLE (-10065 9800);
FORCEPROP 1 LAST SCH_TITLE SYSTEM LEDS
J 0
(-10125 4600);
DISPLAY 1.212766 (-10125 4600);
PAINT ORANGE (-10125 4600);
FORCEPROP 2 LAST CDS_LIB mstr_symbols
J 0
(-2175 4550);
PAINT ORANGE (-2175 4550);
DISPLAY INVISIBLE (-2175 4550);
FORCEPROP 2 LAST PAGE_BORDER TRUE
J 0
(-10065 9800);
DISPLAY 1.021277 (-10065 9800);
PAINT PINK (-10065 9800);
DISPLAY INVISIBLE (-10065 9800);
FORCEPROP 2 LAST ROOM WBG_SPI
J 0
(-10050 9850);
PAINT MONO (-10050 9850);
DISPLAY INVISIBLE (-10050 9850);
FORCEPROP 1 LAST COMMENT_BODY TRUE
J 0
(-2163 4562);
DISPLAY 0.510638 (-2163 4562);
PAINT GREEN (-2163 4562);
DISPLAY INVISIBLE (-2163 4562);
FORCEPROP 2 LAST CDS_XR_PAGE_TITLE CR-177 : @BASEBOARD_FAB2_LIB.BASEBOARD_FAB2(SCH_1):PAGE177
J 0
(-10065 9800);
DISPLAY 0.638298 (-10065 9800);
PAINT PINK (-10065 9800);
DISPLAY INVISIBLE (-10065 9800);
WIRE 16 -1 (-6975 6725)(-6975 6700);
WIRE 16 -1 (-7025 6700)(-6975 6700);
WIRE 16 -1 (-6975 6700)(-6975 6650);
WIRE 16 -1 (-7025 6650)(-7025 6700);
WIRE 16 -1 (-3825 8375)(-3825 8300);
WIRE 16 -1 (-3825 8950)(-3825 9000);
WIRE 16 -1 (-5625 5675)(-5625 5525);
WIRE 16 -1 (-5625 5325)(-5625 5125);
WIRE 16 -1 (-7200 7850)(-7200 7700);
WIRE 16 -1 (-8800 7950)(-8800 8075);
WIRE 16 -1 (-7200 9075)(-7200 8925);
WIRE 16 -1 (-8125 8325)(-8125 8450);
WIRE 16 -1 (-8125 7375)(-8125 7475);
WIRE 16 -1 (-4675 6875)(-4675 6700);
WIRE 3 682 (-5750 7100)(-5750 6100);
WIRE 3 682 (-3850 7100)(-5750 7100);
WIRE 3 682 (-5750 6100)(-3850 6100);
WIRE 3 682 (-3850 6100)(-3850 7100);
WIRE 16 -1 (-8125 7875)(-8125 7950);
WIRE 16 -1 (-8125 7950)(-8125 8125);
WIRE 16 -1 (-8125 7950)(-7400 7950);
FORCEPROP 2 LAST SIG_NAME FM_BMC_FAULT_LED
J 0
(-8085 7960);
DISPLAY 0.617021 (-8085 7960);
PAINT ORANGE (-8085 7960);
FORCEPROP 2 LASTPROP $XRERR UNIQUE?
J 0
(-8325 7960);
DISPLAY 0.638298 (-8325 7960);
PAINT MONO (-8325 7960);
DISPLAY INVISIBLE (-8325 7960);
WIRE 16 -1 (-8000 6325)(-7025 6325);
FORCEPROP 2 LAST SIG_NAME LED_SATA_ACT_R_N
J 0
(-7710 6335);
DISPLAY 0.617021 (-7710 6335);
PAINT ORANGE (-7710 6335);
FORCEPROP 2 LASTPROP $XRERR UNIQUE?
J 0
(-7950 6335);
DISPLAY 0.638298 (-7950 6335);
PAINT MONO (-7950 6335);
DISPLAY INVISIBLE (-7950 6335);
WIRE 16 -1 (-7025 6325)(-6700 6325);
WIRE 16 -1 (-7025 6450)(-7025 6325);
WIRE 16 -1 (-7800 6225)(-6975 6225);
WIRE 16 -1 (-6975 6225)(-6700 6225);
WIRE 16 -1 (-6975 6450)(-6975 6225);
FORCEPROP 2 LAST SIG_NAME LED_SAS_ACT_R_N
J 0
(-7660 6235);
DISPLAY 0.617021 (-7660 6235);
PAINT ORANGE (-7660 6235);
FORCEPROP 2 LASTPROP $XRERR UNIQUE?
J 0
(-7900 6235);
DISPLAY 0.638298 (-7900 6235);
PAINT MONO (-7900 6235);
DISPLAY INVISIBLE (-7900 6235);
WIRE 16 -1 (-6400 6275)(-5650 6275);
FORCEPROP 2 LAST SIG_NAME FP_LED_HDD_ACTIVITY_AND_N
J 0
(-6310 6285);
DISPLAY 0.617021 (-6310 6285);
PAINT ORANGE (-6310 6285);
FORCEPROP 2 LASTPROP $XRERR UNIQUE?
J 0
(-6550 6285);
DISPLAY 0.638298 (-6550 6285);
PAINT MONO (-6550 6285);
DISPLAY INVISIBLE (-6550 6285);
WIRE 16 -1 (-4675 6275)(-5450 6275);
FORCEPROP 2 LAST SIG_NAME FP_LED_HDD_ACTIVITY_AND_R_N
J 0
(-5360 6285);
DISPLAY 0.617021 (-5360 6285);
PAINT ORANGE (-5360 6285);
FORCEPROP 2 LASTPROP $XRERR UNIQUE?
J 0
(-5600 6285);
DISPLAY 0.638298 (-5600 6285);
PAINT MONO (-5600 6285);
DISPLAY INVISIBLE (-5600 6285);
WIRE 16 -1 (-4675 6500)(-4675 6275);
WIRE 16 273 (-4975 7925)(-2275 7925);
WIRE 16 273 (-4975 7925)(-4975 9400);
WIRE 16 -1 (-8800 7750)(-8800 7575);
WIRE 16 -1 (-8800 7575)(-8325 7575);
WIRE 16 -1 (-9025 7575)(-8800 7575);
FORCEPROP 2 LAST SIG_NAME FM_BMC_FAULT_LED_N
J 0
(-8960 7585);
DISPLAY 0.617021 (-8960 7585);
PAINT ORANGE (-8960 7585);
WIRE 16 -1 (-8950 6225)(-8000 6225);
FORCEPROP 2 LAST SIG_NAME LED_PCH_SSATA_HDD_N
J 0
(-8935 6235);
DISPLAY 0.617021 (-8935 6235);
PAINT ORANGE (-8935 6235);
WIRE 16 -1 (-8950 6325)(-8200 6325);
FORCEPROP 2 LAST SIG_NAME LED_PCH_SATA_HDD_N
J 0
(-8935 6335);
DISPLAY 0.617021 (-8935 6335);
PAINT ORANGE (-8935 6335);
WIRE 16 -1 (-7200 8250)(-7200 8375);
FORCEPROP 2 LAST SIG_NAME FM_RED_LED_CATHODE
J 0
(-7160 8310);
DISPLAY 0.617021 (-7160 8310);
PAINT ORANGE (-7160 8310);
FORCEPROP 2 LASTPROP $XRERR UNIQUE?
J 0
(-7400 8310);
DISPLAY 0.638298 (-7400 8310);
PAINT MONO (-7400 8310);
DISPLAY INVISIBLE (-7400 8310);
WIRE 16 -1 (-7200 8575)(-7200 8725);
FORCEPROP 2 LAST SIG_NAME FM_RED_LED_ANODE
J 0
(-7160 8610);
DISPLAY 0.617021 (-7160 8610);
PAINT ORANGE (-7160 8610);
FORCEPROP 2 LASTPROP $XRERR UNIQUE?
J 0
(-7400 8610);
DISPLAY 0.638298 (-7400 8610);
PAINT MONO (-7400 8610);
DISPLAY INVISIBLE (-7400 8610);
WIRE 16 -1 (-3825 8750)(-3825 8575);
FORCEPROP 2 LAST SIG_NAME LED_P5V_STBY
J 0
(-3800 8610);
DISPLAY 0.617021 (-3800 8610);
PAINT ORANGE (-3800 8610);
FORCEPROP 2 LASTPROP $XRERR UNIQUE?
J 0
(-4040 8610);
DISPLAY 0.638298 (-4040 8610);
PAINT MONO (-4040 8610);
DISPLAY INVISIBLE (-4040 8610);
DOT 1 (-8800 7575);
DOT 1 (-8125 7950);
DOT 1 (-7025 6325);
DOT 1 (-6975 6700);
DOT 1 (-6975 6225);
FORCENOTE
TP FAB1 CHANGE RES AND LED 0422
(-5750 6025) 0;
DISPLAY LEFT (-5750 6025);
DISPLAY 1.021277 (-5750 6025);
PAINT RED (-5750 6025);
FORCENOTE
POWER PINS
(-7150 5700) 0;
DISPLAY LEFT (-7150 5700);
DISPLAY 1.021277 (-7150 5700);
PAINT PURPLE (-7150 5700);
FORCENOTE
CAD NOTE:
(-7175 5800) 0;
DISPLAY LEFT (-7175 5800);
DISPLAY 1.021277 (-7175 5800);
PAINT PURPLE (-7175 5800);
FORCENOTE
ROOM=MIO_CHASSIS
(-10105 4748) 0;
DISPLAY LEFT (-10105 4748);
DISPLAY 0.617021 (-10105 4748);
PAINT PURPLE (-10105 4748);
FORCENOTE
ADD 0.1UF CAPS FOR VCC
(-7175 5750) 0;
DISPLAY LEFT (-7175 5750);
DISPLAY 1.021277 (-7175 5750);
PAINT PURPLE (-7175 5750);
QUIT
